# T6G (Grand Teton) — schematic netlist excerpt (pin names and nets, part order shuffled) for the footprints in the layout excerpt that follows; sources: Cadence DE-HDL packaged netlist, KiCad conversion of 04192023_DAF0TMB3IC0_F0TG_MB_C_brd_V02_OCP.brd

C306  Q_CAP  1UF 4V 20% X6S  pkg 0201  page 334 : A = P0V9_CPU1_RT1_2A_2D ; B = GND
C2143  Q_CAP  22UF 4V 20% X6S  pkg C0402  page 68 : A = PVDDCR_SOC_P0 ; B = GND
PC627_4  Q_CAP  22UF 16V 20% X6S  pkg C0805  page 223 : A = SW_P12V_AUX_PVDDIO_P1_FLT ; B = GND

(kicad_pcb
	(version 20260206)
	(generator "pcbnew")
	(generator_version "10.0")
	(general
		(thickness 1.6)
		(legacy_teardrops no)
	)
	(paper "A4")
	(title_block
		(title "04192023_DAF0TMB3IC0_F0TG_MB_C_brd_V02_OCP.brd")
		(comment 1 "Grand Teton / footprints 6292-6294 of 8354")
	)
	(layers
		(0 "F.Cu" signal "TOP")
		(4 "In1.Cu" signal "GND")
		(6 "In2.Cu" signal "IN1")
		(8 "In3.Cu" signal "GND1")
		(10 "In4.Cu" signal "IN2")
		(12 "In5.Cu" signal "GND2")
		(14 "In6.Cu" signal "IN3")
		(16 "In7.Cu" signal "GND3")
		(18 "In8.Cu" signal "VCC")
		(20 "In9.Cu" signal "VCC1")
		(22 "In10.Cu" signal "GND4")
		(24 "In11.Cu" signal "IN4")
		(26 "In12.Cu" signal "GND5")
		(28 "In13.Cu" signal "IN5")
		(30 "In14.Cu" signal "GND6")
		(32 "In15.Cu" signal "IN6")
		(34 "In16.Cu" signal "GND7")
		(2 "B.Cu" signal "BOTTOM")
		(9 "F.Adhes" user "F.Adhesive")
		(11 "B.Adhes" user "B.Adhesive")
		(13 "F.Paste" user "Package Geometry/Pastemask Top")
		(15 "B.Paste" user "Package Geometry/Pastemask Bottom")
		(5 "F.SilkS" user "Ref Des/Silkscreen Top")
		(7 "B.SilkS" user "Ref Des/Silkscreen Bottom")
		(1 "F.Mask" user "Board Geometry/Soldermask Top")
		(3 "B.Mask" user "Board Geometry/Soldermask Bottom")
		(17 "Dwgs.User" user "User.Drawings")
		(19 "Cmts.User" user "User.Comments")
		(21 "Eco1.User" user "User.Eco1")
		(23 "Eco2.User" user "User.Eco2")
		(25 "Edge.Cuts" user "Board Geometry/Outline")
		(27 "Margin" user)
		(31 "F.CrtYd" user "Package Geometry/Place Bound Top")
		(29 "B.CrtYd" user "Package Geometry/Place Bound Bottom")
		(35 "F.Fab" user "Ref Des/Assembly Top")
		(33 "B.Fab" user "Ref Des/Assembly Bottom")
	)
	(footprint ""
		(layer "B.Cu")
		(at 367.233454 -253.43231)
		(property "Reference" "C2143"
			(at 0 0 0)
			(layer "B.SilkS")
			(hide yes)
			(effects
				(font
					(size 1.27 1.27)
				)
				(justify mirror)
			)
		)
		(property "Value" ""
			(at 0 0 0)
			(layer "B.Fab")
			(effects
				(font
					(size 1.27 1.27)
				)
				(justify mirror)
			)
		)
		(duplicate_pad_numbers_are_jumpers no)
		(fp_line
			(start -0.7874 -0.4064)
			(end -0.7874 0.4064)
			(stroke
				(width 0.1524)
				(type default)
			)
			(layer "B.SilkS")
		)
		(fp_line
			(start -0.7874 0.4064)
			(end 0.7874 0.4064)
			(stroke
				(width 0.1524)
				(type default)
			)
			(layer "B.SilkS")
		)
		(fp_line
			(start 0.7874 -0.4064)
			(end -0.7874 -0.4064)
			(stroke
				(width 0.1524)
				(type default)
			)
			(layer "B.SilkS")
		)
		(fp_line
			(start 0.7874 0.4064)
			(end 0.7874 -0.4064)
			(stroke
				(width 0.1524)
				(type default)
			)
			(layer "B.SilkS")
		)
		(fp_line
			(start -0.67945 -0.3048)
			(end -0.67945 0.3048)
			(stroke
				(width 0.1)
				(type default)
			)
			(layer "B.Fab")
		)
		(fp_line
			(start -0.67945 0.3048)
			(end -0.120396 0.3048)
			(stroke
				(width 0.1)
				(type default)
			)
			(layer "B.Fab")
		)
		(fp_line
			(start -0.12065 -0.3048)
			(end -0.67945 -0.3048)
			(stroke
				(width 0.1)
				(type default)
			)
			(layer "B.Fab")
		)
		(fp_line
			(start -0.12065 -0.2794)
			(end -0.12065 -0.3048)
			(stroke
				(width 0.1)
				(type default)
			)
			(layer "B.Fab")
		)
		(fp_line
			(start -0.120396 0.2794)
			(end 0.12065 0.2794)
			(stroke
				(width 0.1)
				(type default)
			)
			(layer "B.Fab")
		)
		(fp_line
			(start -0.120396 0.3048)
			(end -0.120396 0.2794)
			(stroke
				(width 0.1)
				(type default)
			)
			(layer "B.Fab")
		)
		(fp_line
			(start 0.12065 -0.305054)
			(end 0.12065 -0.2794)
			(stroke
				(width 0.1)
				(type default)
			)
			(layer "B.Fab")
		)
		(fp_line
			(start 0.12065 -0.2794)
			(end -0.12065 -0.2794)
			(stroke
				(width 0.1)
				(type default)
			)
			(layer "B.Fab")
		)
		(fp_line
			(start 0.12065 0.2794)
			(end 0.12065 0.3048)
			(stroke
				(width 0.1)
				(type default)
			)
			(layer "B.Fab")
		)
		(fp_line
			(start 0.12065 0.3048)
			(end 0.67945 0.3048)
			(stroke
				(width 0.1)
				(type default)
			)
			(layer "B.Fab")
		)
		(fp_line
			(start 0.67945 -0.305054)
			(end 0.12065 -0.305054)
			(stroke
				(width 0.1)
				(type default)
			)
			(layer "B.Fab")
		)
		(fp_line
			(start 0.67945 0.3048)
			(end 0.67945 -0.305054)
			(stroke
				(width 0.1)
				(type default)
			)
			(layer "B.Fab")
		)
		(pad "1" smd circle
			(at 0.40005 0 180)
			(size 0 0)
			(layers "B.Cu" "B.Mask" "B.Paste")
			(net "PVDDCR_SOC_P0")
		)
		(pad "2" smd circle
			(at -0.40005 0 180)
			(size 0 0)
			(layers "B.Cu" "B.Mask" "B.Paste")
			(net "GND")
		)
	)
	(footprint ""
		(layer "B.Cu")
		(at 84.706206 -386.766562 90)
		(property "Reference" "C306"
			(at 0 0 90)
			(layer "B.SilkS")
			(hide yes)
			(effects
				(font
					(size 1.27 1.27)
				)
				(justify mirror)
			)
		)
		(property "Value" ""
			(at 0 0 90)
			(layer "B.Fab")
			(effects
				(font
					(size 1.27 1.27)
				)
				(justify mirror)
			)
		)
		(duplicate_pad_numbers_are_jumpers no)
		(fp_line
			(start 0.299974 -0.150114)
			(end -0.299974 -0.150114)
			(stroke
				(width 0.1)
				(type default)
			)
			(layer "B.Fab")
		)
		(fp_line
			(start -0.299974 -0.150114)
			(end -0.299974 0.150114)
			(stroke
				(width 0.1)
				(type default)
			)
			(layer "B.Fab")
		)
		(fp_line
			(start 0.299974 0.150114)
			(end 0.299974 -0.150114)
			(stroke
				(width 0.1)
				(type default)
			)
			(layer "B.Fab")
		)
		(fp_line
			(start -0.299974 0.150114)
			(end 0.299974 0.150114)
			(stroke
				(width 0.1)
				(type default)
			)
			(layer "B.Fab")
		)
		(pad "1" smd rect
			(at 0.2667 0 270)
			(size 0.3048 0.381)
			(layers "B.Cu" "B.Mask" "B.Paste")
			(net "P0V9_CPU1_RT1_2A_2D")
		)
		(pad "2" smd rect
			(at -0.2667 0 270)
			(size 0.3048 0.381)
			(layers "B.Cu" "B.Mask" "B.Paste")
			(net "GND")
		)
	)
	(footprint ""
		(layer "B.Cu")
		(at 31.85033 -346.788994 90)
		(property "Reference" "PC627_4"
			(at 0 0 90)
			(layer "B.SilkS")
			(hide yes)
			(effects
				(font
					(size 1.27 1.27)
				)
				(justify mirror)
			)
		)
		(property "Value" ""
			(at 0 0 90)
			(layer "B.Fab")
			(effects
				(font
					(size 1.27 1.27)
				)
				(justify mirror)
			)
		)
		(duplicate_pad_numbers_are_jumpers no)
		(fp_line
			(start 1.524 -0.762)
			(end -1.524 -0.762)
			(stroke
				(width 0.1524)
				(type default)
			)
			(layer "B.SilkS")
		)
		(fp_line
			(start -1.524 -0.762)
			(end -1.524 0.762)
			(stroke
				(width 0.1524)
				(type default)
			)
			(layer "B.SilkS")
		)
		(fp_line
			(start 1.524 0.762)
			(end 1.524 -0.762)
			(stroke
				(width 0.1524)
				(type default)
			)
			(layer "B.SilkS")
		)
		(fp_line
			(start -1.524 0.762)
			(end 1.524 0.762)
			(stroke
				(width 0.1524)
				(type default)
			)
			(layer "B.SilkS")
		)
		(fp_line
			(start 1.1049 -0.724916)
			(end 1.1049 0.724916)
			(stroke
				(width 0.1)
				(type default)
			)
			(layer "B.Fab")
		)
		(fp_line
			(start -1.1049 -0.724916)
			(end 1.1049 -0.724916)
			(stroke
				(width 0.1)
				(type default)
			)
			(layer "B.Fab")
		)
		(fp_line
			(start 1.1049 0.724916)
			(end -1.1049 0.724916)
			(stroke
				(width 0.1)
				(type default)
			)
			(layer "B.Fab")
		)
		(fp_line
			(start -1.1049 0.724916)
			(end -1.1049 -0.724916)
			(stroke
				(width 0.1)
				(type default)
			)
			(layer "B.Fab")
		)
		(pad "1" smd rect
			(at 0.889 0 90)
			(size 1.016 1.27)
			(layers "B.Cu" "B.Mask" "B.Paste")
			(net "SW_P12V_AUX_PVDDIO_P1_FLT")
		)
		(pad "2" smd rect
			(at -0.889 0 90)
			(size 1.016 1.27)
			(layers "B.Cu" "B.Mask" "B.Paste")
			(net "GND")
		)
	)
)
